(kicad_pcb
	(version 20241229)
	(generator "pcbnew")
	(generator_version "9.0")
	(general
		(thickness 1.599998)
		(legacy_teardrops no)
	)
	(paper "A4")
	(title_block
		(title "Artix - Datacenter Secure Control Module (DC-SCM)")
		(date "2024-11-06")
		(rev "1.1.3")
		(comment 9 "footprints 339-344 of 544")
	)
	(layers
		(0 "F.Cu" signal)
		(4 "In1.Cu" signal)
		(6 "In2.Cu" signal)
		(8 "In3.Cu" signal)
		(10 "In4.Cu" signal)
		(12 "In5.Cu" signal)
		(14 "In6.Cu" signal)
		(2 "B.Cu" signal)
		(9 "F.Adhes" user "F.Adhesive")
		(11 "B.Adhes" user "B.Adhesive")
		(13 "F.Paste" user)
		(15 "B.Paste" user)
		(5 "F.SilkS" user "F.Silkscreen")
		(7 "B.SilkS" user "B.Silkscreen")
		(1 "F.Mask" user)
		(3 "B.Mask" user)
		(17 "Dwgs.User" user "User.Drawings")
		(19 "Cmts.User" user "User.Comments")
		(21 "Eco1.User" user "User.Eco1")
		(23 "Eco2.User" user "User.Eco2")
		(25 "Edge.Cuts" user)
		(27 "Margin" user)
		(31 "F.CrtYd" user "F.Courtyard")
		(29 "B.CrtYd" user "B.Courtyard")
		(35 "F.Fab" user)
		(33 "B.Fab" user)
	)
	(footprint "antmicro-footprints:R_0402_1005Metric"
		(layer "B.Cu")
		(at 91.975 160.875 180)
		(descr "Resistor SMD 0402")
		(tags "resistor SMD 0402")
		(property "Reference" "R115"
			(at 0.775 -0.325 0)
			(layer "B.SilkS")
			(effects
				(font
					(size 0.7 0.7)
					(thickness 0.15)
				)
				(justify left bottom mirror)
			)
		)
		(property "Value" "R_0R_0402"
			(at 0 -1.4 0)
			(layer "B.Fab")
			(effects
				(font
					(size 0.7 0.7)
					(thickness 0.15)
				)
				(justify left bottom mirror)
			)
		)
		(property "Datasheet" "https://industrial.panasonic.com/cdbs/www-data/pdf/RDA0000/AOA0000C301.pdf"
			(at 0 0 180)
			(layer "F.Fab")
			(hide yes)
			(effects
				(font
					(size 1.27 1.27)
					(thickness 0.15)
				)
			)
		)
		(property "Description" "SMD Chip Resistor, Jumper, 0 ohm, 100 mW, 0402 [1005 Metric], Thick Film, General Purpose"
			(at 0 0 180)
			(layer "F.Fab")
			(hide yes)
			(effects
				(font
					(size 1.27 1.27)
					(thickness 0.15)
				)
			)
		)
		(property "Author" "Antmicro"
			(at 183.95 321.75 0)
			(layer "B.Fab")
			(hide yes)
			(effects
				(font
					(size 1 1)
					(thickness 0.15)
				)
				(justify mirror)
			)
		)
		(property "Current" "1A"
			(at 183.95 321.75 0)
			(layer "B.Fab")
			(hide yes)
			(effects
				(font
					(size 1 1)
					(thickness 0.15)
				)
				(justify mirror)
			)
		)
		(property "License" "Apache-2.0"
			(at 183.95 321.75 0)
			(layer "B.Fab")
			(hide yes)
			(effects
				(font
					(size 1 1)
					(thickness 0.15)
				)
				(justify mirror)
			)
		)
		(property "MPN" "ERJ2GE0R00X"
			(at 183.95 321.75 0)
			(layer "B.Fab")
			(hide yes)
			(effects
				(font
					(size 1 1)
					(thickness 0.15)
				)
				(justify mirror)
			)
		)
		(property "Manufacturer" "Panasonic"
			(at 183.95 321.75 0)
			(layer "B.Fab")
			(hide yes)
			(effects
				(font
					(size 1 1)
					(thickness 0.15)
				)
				(justify mirror)
			)
		)
		(property "Tolerance" "~"
			(at 183.95 321.75 0)
			(layer "B.Fab")
			(hide yes)
			(effects
				(font
					(size 1 1)
					(thickness 0.15)
				)
				(justify mirror)
			)
		)
		(property "Val" "0R"
			(at 183.95 321.75 0)
			(layer "B.Fab")
			(hide yes)
			(effects
				(font
					(size 1 1)
					(thickness 0.15)
				)
				(justify mirror)
			)
		)
		(sheetname "/Edge connector/")
		(sheetfile "edge-connector.kicad_sch")
		(attr smd)
		(fp_rect
			(start -0.925 0.47)
			(end 0.925 -0.47)
			(stroke
				(width 0.05)
				(type default)
			)
			(fill no)
			(layer "B.CrtYd")
		)
		(fp_rect
			(start -0.5 0.25)
			(end 0.5 -0.25)
			(stroke
				(width 0.15)
				(type solid)
			)
			(fill no)
			(layer "B.Fab")
		)
		(pad "1" smd roundrect
			(at -0.48 0 180)
			(size 0.59 0.64)
			(layers "B.Cu" "B.Mask" "B.Paste")
			(roundrect_rratio 0.25)
			(net 522 "VIRTUAL_RESEAT_R")
			(pintype "passive")
		)
		(pad "2" smd roundrect
			(at 0.48 0 180)
			(size 0.59 0.64)
			(layers "B.Cu" "B.Mask" "B.Paste")
			(roundrect_rratio 0.25)
			(net 244 "/Edge connector/VIRTUAL_RESEAT")
			(pintype "passive")
		)
	)
	(footprint "antmicro-footprints:R_0402_1005Metric"
		(layer "B.Cu")
		(at 95.25 91.055 -90)
		(descr "Resistor SMD 0402")
		(tags "resistor SMD 0402")
		(property "Reference" "R166"
			(at -3.965 0.565 90)
			(layer "B.SilkS")
			(effects
				(font
					(size 0.7 0.7)
					(thickness 0.15)
				)
				(justify left bottom mirror)
			)
		)
		(property "Value" "R_220R_0402"
			(at 0 -1.4 90)
			(layer "B.Fab")
			(effects
				(font
					(size 0.7 0.7)
					(thickness 0.15)
				)
				(justify left bottom mirror)
			)
		)
		(property "Datasheet" "https://www.bourns.com/docs/product-datasheets/cr.pdf"
			(at 0 0 270)
			(layer "F.Fab")
			(hide yes)
			(effects
				(font
					(size 1.27 1.27)
					(thickness 0.15)
				)
			)
		)
		(property "Description" "SMD Chip Resistor, 220 ohm, ± 1%, 62.5 mW, 0402 [1005 Metric], Thick Film, General Purpose"
			(at 0 0 270)
			(layer "F.Fab")
			(hide yes)
			(effects
				(font
					(size 1.27 1.27)
					(thickness 0.15)
				)
			)
		)
		(property "Author" "Antmicro"
			(at 4.195 186.305 0)
			(layer "B.Fab")
			(hide yes)
			(effects
				(font
					(size 1 1)
					(thickness 0.15)
				)
				(justify mirror)
			)
		)
		(property "License" "Apache-2.0"
			(at 4.195 186.305 0)
			(layer "B.Fab")
			(hide yes)
			(effects
				(font
					(size 1 1)
					(thickness 0.15)
				)
				(justify mirror)
			)
		)
		(property "MPN" "CR0402-FX-2200GLF"
			(at 4.195 186.305 0)
			(layer "B.Fab")
			(hide yes)
			(effects
				(font
					(size 1 1)
					(thickness 0.15)
				)
				(justify mirror)
			)
		)
		(property "Manufacturer" "Bourns"
			(at 4.195 186.305 0)
			(layer "B.Fab")
			(hide yes)
			(effects
				(font
					(size 1 1)
					(thickness 0.15)
				)
				(justify mirror)
			)
		)
		(property "Tolerance" "1%"
			(at 4.195 186.305 0)
			(layer "B.Fab")
			(hide yes)
			(effects
				(font
					(size 1 1)
					(thickness 0.15)
				)
				(justify mirror)
			)
		)
		(property "Val" "220R"
			(at 4.195 186.305 0)
			(layer "B.Fab")
			(hide yes)
			(effects
				(font
					(size 1 1)
					(thickness 0.15)
				)
				(justify mirror)
			)
		)
		(sheetname "/Ethernet/")
		(sheetfile "ethernet.kicad_sch")
		(attr smd)
		(fp_rect
			(start -0.925 0.47)
			(end 0.925 -0.47)
			(stroke
				(width 0.05)
				(type default)
			)
			(fill no)
			(layer "B.CrtYd")
		)
		(fp_rect
			(start -0.5 0.25)
			(end 0.5 -0.25)
			(stroke
				(width 0.15)
				(type solid)
			)
			(fill no)
			(layer "B.Fab")
		)
		(pad "1" smd roundrect
			(at -0.48 0 270)
			(size 0.59 0.64)
			(layers "B.Cu" "B.Mask" "B.Paste")
			(roundrect_rratio 0.25)
			(net 574 "Net-(J1-Pad15)")
			(pintype "passive")
		)
		(pad "2" smd roundrect
			(at 0.48 0 270)
			(size 0.59 0.64)
			(layers "B.Cu" "B.Mask" "B.Paste")
			(roundrect_rratio 0.25)
			(net 416 "/Ethernet/ETH_LED2")
			(pintype "passive")
		)
	)
	(footprint "antmicro-footprints:R_0402_1005Metric"
		(layer "B.Cu")
		(at 76.675 158.475 90)
		(descr "Resistor SMD 0402")
		(tags "resistor SMD 0402")
		(property "Reference" "R134"
			(at -3.625 0.425 90)
			(layer "B.SilkS")
			(effects
				(font
					(size 0.7 0.7)
					(thickness 0.15)
				)
				(justify right bottom mirror)
			)
		)
		(property "Value" "R_4k7_0402"
			(at 0 -1.4 90)
			(layer "B.Fab")
			(effects
				(font
					(size 0.7 0.7)
					(thickness 0.15)
				)
				(justify right bottom mirror)
			)
		)
		(property "Datasheet" "https://www.bourns.com/docs/product-datasheets/cr.pdf"
			(at 0 0 90)
			(layer "F.Fab")
			(hide yes)
			(effects
				(font
					(size 1.27 1.27)
					(thickness 0.15)
				)
			)
		)
		(property "Description" "SMD Chip Resistor, 4.7 kohm, ± 1%, 62.5 mW, 0402 [1005 Metric], Thick Film, General Purpose"
			(at 0 0 90)
			(layer "F.Fab")
			(hide yes)
			(effects
				(font
					(size 1.27 1.27)
					(thickness 0.15)
				)
			)
		)
		(property "Author" "Antmicro"
			(at 235.15 81.8 0)
			(layer "B.Fab")
			(hide yes)
			(effects
				(font
					(size 1 1)
					(thickness 0.15)
				)
				(justify mirror)
			)
		)
		(property "License" "Apache-2.0"
			(at 235.15 81.8 0)
			(layer "B.Fab")
			(hide yes)
			(effects
				(font
					(size 1 1)
					(thickness 0.15)
				)
				(justify mirror)
			)
		)
		(property "MPN" "CR0402-FX-4701GLF"
			(at 235.15 81.8 0)
			(layer "B.Fab")
			(hide yes)
			(effects
				(font
					(size 1 1)
					(thickness 0.15)
				)
				(justify mirror)
			)
		)
		(property "Manufacturer" "Bourns"
			(at 235.15 81.8 0)
			(layer "B.Fab")
			(hide yes)
			(effects
				(font
					(size 1 1)
					(thickness 0.15)
				)
				(justify mirror)
			)
		)
		(property "Tolerance" "1%"
			(at 235.15 81.8 0)
			(layer "B.Fab")
			(hide yes)
			(effects
				(font
					(size 1 1)
					(thickness 0.15)
				)
				(justify mirror)
			)
		)
		(property "Val" "4k7"
			(at 235.15 81.8 0)
			(layer "B.Fab")
			(hide yes)
			(effects
				(font
					(size 1 1)
					(thickness 0.15)
				)
				(justify mirror)
			)
		)
		(sheetname "/FPGA banks 13-16/")
		(sheetfile "fpga-banks-13-16.kicad_sch")
		(attr smd)
		(fp_rect
			(start -0.925 0.47)
			(end 0.925 -0.47)
			(stroke
				(width 0.05)
				(type default)
			)
			(fill no)
			(layer "B.CrtYd")
		)
		(fp_rect
			(start -0.5 0.25)
			(end 0.5 -0.25)
			(stroke
				(width 0.15)
				(type solid)
			)
			(fill no)
			(layer "B.Fab")
		)
		(pad "1" smd roundrect
			(at -0.48 0 90)
			(size 0.59 0.64)
			(layers "B.Cu" "B.Mask" "B.Paste")
			(roundrect_rratio 0.25)
			(net 2 "VCC3V3")
			(pintype "passive")
		)
		(pad "2" smd roundrect
			(at 0.48 0 90)
			(size 0.59 0.64)
			(layers "B.Cu" "B.Mask" "B.Paste")
			(roundrect_rratio 0.25)
			(net 332 "ROT_QSPI_DQ2")
			(pintype "passive")
		)
	)
	(footprint "antmicro-footprints:C_0402_1005Metric"
		(layer "B.Cu")
		(at 93.775 124.375)
		(descr "Capacitor SMD 0402")
		(tags "capacitor SMD 0402")
		(property "Reference" "C134"
			(at -1.375 1.325 0)
			(layer "B.SilkS")
			(effects
				(font
					(size 0.7 0.7)
					(thickness 0.15)
				)
				(justify right bottom mirror)
			)
		)
		(property "Value" "C_100n_6V3_0402"
			(at 0 -1.4 0)
			(layer "B.Fab")
			(effects
				(font
					(size 0.7 0.7)
					(thickness 0.15)
				)
				(justify right bottom mirror)
			)
		)
		(property "Datasheet" "https://www.passivecomponent.com/wp-content/uploads/datasheet/WTC_MLCC_General_Purpose.pdf"
			(at 0 0 0)
			(layer "F.Fab")
			(hide yes)
			(effects
				(font
					(size 1.27 1.27)
					(thickness 0.15)
				)
			)
		)
		(property "Description" "SMT Multilayer Ceramic Capacitor, 0.1 µF, 6.3 V, 0402 [1005 Metric], ± 10%, X5R, Walsin MLCC"
			(at 0 0 0)
			(layer "F.Fab")
			(hide yes)
			(effects
				(font
					(size 1.27 1.27)
					(thickness 0.15)
				)
			)
		)
		(property "Author" "Antmicro"
			(at 0 0 0)
			(layer "B.Fab")
			(hide yes)
			(effects
				(font
					(size 1 1)
					(thickness 0.15)
				)
				(justify mirror)
			)
		)
		(property "Dielectric" ""
			(at 0 0 0)
			(layer "B.Fab")
			(hide yes)
			(effects
				(font
					(size 1 1)
					(thickness 0.15)
				)
				(justify mirror)
			)
		)
		(property "License" "Apache-2.0"
			(at 0 0 0)
			(layer "B.Fab")
			(hide yes)
			(effects
				(font
					(size 1 1)
					(thickness 0.15)
				)
				(justify mirror)
			)
		)
		(property "MPN" "0402X104K6R3CT"
			(at 0 0 0)
			(layer "B.Fab")
			(hide yes)
			(effects
				(font
					(size 1 1)
					(thickness 0.15)
				)
				(justify mirror)
			)
		)
		(property "Manufacturer" "Walsin"
			(at 0 0 0)
			(layer "B.Fab")
			(hide yes)
			(effects
				(font
					(size 1 1)
					(thickness 0.15)
				)
				(justify mirror)
			)
		)
		(property "Public" "False"
			(at 0 0 0)
			(layer "B.Fab")
			(hide yes)
			(effects
				(font
					(size 1 1)
					(thickness 0.15)
				)
				(justify mirror)
			)
		)
		(property "Val" "100n"
			(at 0 0 0)
			(layer "B.Fab")
			(hide yes)
			(effects
				(font
					(size 1 1)
					(thickness 0.15)
				)
				(justify mirror)
			)
		)
		(property "Voltage" ""
			(at 0 0 0)
			(layer "B.Fab")
			(hide yes)
			(effects
				(font
					(size 1 1)
					(thickness 0.15)
				)
				(justify mirror)
			)
		)
		(sheetname "/Interfaces/")
		(sheetfile "interfaces.kicad_sch")
		(attr smd)
		(fp_rect
			(start -0.925 0.47)
			(end 0.925 -0.47)
			(stroke
				(width 0.05)
				(type default)
			)
			(fill no)
			(layer "B.CrtYd")
		)
		(fp_line
			(start -0.494 -0.248)
			(end -0.494 0.25)
			(stroke
				(width 0.15)
				(type solid)
			)
			(layer "B.Fab")
		)
		(fp_line
			(start -0.494 0.25)
			(end 0.504 0.25)
			(stroke
				(width 0.15)
				(type solid)
			)
			(layer "B.Fab")
		)
		(fp_line
			(start 0.504 -0.248)
			(end -0.494 -0.248)
			(stroke
				(width 0.15)
				(type solid)
			)
			(layer "B.Fab")
		)
		(fp_line
			(start 0.504 0.25)
			(end 0.504 -0.248)
			(stroke
				(width 0.15)
				(type solid)
			)
			(layer "B.Fab")
		)
		(pad "1" smd roundrect
			(at -0.48 0)
			(size 0.59 0.64)
			(layers "B.Cu" "B.Mask" "B.Paste")
			(roundrect_rratio 0.25)
			(net 1 "GND")
			(pintype "passive")
		)
		(pad "2" smd roundrect
			(at 0.48 0)
			(size 0.59 0.64)
			(layers "B.Cu" "B.Mask" "B.Paste")
			(roundrect_rratio 0.25)
			(net 6 "VCC1V0")
			(pintype "passive")
		)
	)
	(footprint "antmicro-footprints:C_0402_1005Metric"
		(layer "B.Cu")
		(at 93.775 126.375)
		(descr "Capacitor SMD 0402")
		(tags "capacitor SMD 0402")
		(property "Reference" "C136"
			(at -3.675 0.325 0)
			(layer "B.SilkS")
			(effects
				(font
					(size 0.7 0.7)
					(thickness 0.15)
				)
				(justify right bottom mirror)
			)
		)
		(property "Value" "C_100n_6V3_0402"
			(at 0 -1.4 0)
			(layer "B.Fab")
			(effects
				(font
					(size 0.7 0.7)
					(thickness 0.15)
				)
				(justify right bottom mirror)
			)
		)
		(property "Datasheet" "https://www.passivecomponent.com/wp-content/uploads/datasheet/WTC_MLCC_General_Purpose.pdf"
			(at 0 0 0)
			(layer "F.Fab")
			(hide yes)
			(effects
				(font
					(size 1.27 1.27)
					(thickness 0.15)
				)
			)
		)
		(property "Description" "SMT Multilayer Ceramic Capacitor, 0.1 µF, 6.3 V, 0402 [1005 Metric], ± 10%, X5R, Walsin MLCC"
			(at 0 0 0)
			(layer "F.Fab")
			(hide yes)
			(effects
				(font
					(size 1.27 1.27)
					(thickness 0.15)
				)
			)
		)
		(property "Author" "Antmicro"
			(at 0 0 0)
			(layer "B.Fab")
			(hide yes)
			(effects
				(font
					(size 1 1)
					(thickness 0.15)
				)
				(justify mirror)
			)
		)
		(property "Dielectric" ""
			(at 0 0 0)
			(layer "B.Fab")
			(hide yes)
			(effects
				(font
					(size 1 1)
					(thickness 0.15)
				)
				(justify mirror)
			)
		)
		(property "License" "Apache-2.0"
			(at 0 0 0)
			(layer "B.Fab")
			(hide yes)
			(effects
				(font
					(size 1 1)
					(thickness 0.15)
				)
				(justify mirror)
			)
		)
		(property "MPN" "0402X104K6R3CT"
			(at 0 0 0)
			(layer "B.Fab")
			(hide yes)
			(effects
				(font
					(size 1 1)
					(thickness 0.15)
				)
				(justify mirror)
			)
		)
		(property "Manufacturer" "Walsin"
			(at 0 0 0)
			(layer "B.Fab")
			(hide yes)
			(effects
				(font
					(size 1 1)
					(thickness 0.15)
				)
				(justify mirror)
			)
		)
		(property "Public" "False"
			(at 0 0 0)
			(layer "B.Fab")
			(hide yes)
			(effects
				(font
					(size 1 1)
					(thickness 0.15)
				)
				(justify mirror)
			)
		)
		(property "Val" "100n"
			(at 0 0 0)
			(layer "B.Fab")
			(hide yes)
			(effects
				(font
					(size 1 1)
					(thickness 0.15)
				)
				(justify mirror)
			)
		)
		(property "Voltage" ""
			(at 0 0 0)
			(layer "B.Fab")
			(hide yes)
			(effects
				(font
					(size 1 1)
					(thickness 0.15)
				)
				(justify mirror)
			)
		)
		(sheetname "/Interfaces/")
		(sheetfile "interfaces.kicad_sch")
		(attr smd)
		(fp_rect
			(start -0.925 0.47)
			(end 0.925 -0.47)
			(stroke
				(width 0.05)
				(type default)
			)
			(fill no)
			(layer "B.CrtYd")
		)
		(fp_line
			(start -0.494 -0.248)
			(end -0.494 0.25)
			(stroke
				(width 0.15)
				(type solid)
			)
			(layer "B.Fab")
		)
		(fp_line
			(start -0.494 0.25)
			(end 0.504 0.25)
			(stroke
				(width 0.15)
				(type solid)
			)
			(layer "B.Fab")
		)
		(fp_line
			(start 0.504 -0.248)
			(end -0.494 -0.248)
			(stroke
				(width 0.15)
				(type solid)
			)
			(layer "B.Fab")
		)
		(fp_line
			(start 0.504 0.25)
			(end 0.504 -0.248)
			(stroke
				(width 0.15)
				(type solid)
			)
			(layer "B.Fab")
		)
		(pad "1" smd roundrect
			(at -0.48 0)
			(size 0.59 0.64)
			(layers "B.Cu" "B.Mask" "B.Paste")
			(roundrect_rratio 0.25)
			(net 1 "GND")
			(pintype "passive")
		)
		(pad "2" smd roundrect
			(at 0.48 0)
			(size 0.59 0.64)
			(layers "B.Cu" "B.Mask" "B.Paste")
			(roundrect_rratio 0.25)
			(net 6 "VCC1V0")
			(pintype "passive")
		)
	)
	(footprint "antmicro-footprints:C_0603_1608Metric"
		(layer "B.Cu")
		(at 93.575 120.675)
		(descr "Capacitor SMD 0603")
		(tags "capacitor 0603")
		(property "Reference" "C190"
			(at -1.575 -2.275 0)
			(layer "B.SilkS")
			(effects
				(font
					(size 0.7 0.7)
					(thickness 0.15)
				)
				(justify right bottom mirror)
			)
		)
		(property "Value" "C_4u7_0603"
			(at 0 -1.6 0)
			(layer "B.Fab")
			(effects
				(font
					(size 0.7 0.7)
					(thickness 0.15)
				)
				(justify right bottom mirror)
			)
		)
		(property "Datasheet" "https://product.tdk.com/en/search/capacitor/ceramic/mlcc/info?part_no=C1608X5R1V475M080AC"
			(at 0 0 0)
			(layer "F.Fab")
			(hide yes)
			(effects
				(font
					(size 1.27 1.27)
					(thickness 0.15)
				)
			)
		)
		(property "Description" "SMD Multilayer Ceramic Capacitor, 4.7 µF, 35 V, 0603 [1608 Metric], ± 20%, X5R, C"
			(at 0 0 0)
			(layer "F.Fab")
			(hide yes)
			(effects
				(font
					(size 1.27 1.27)
					(thickness 0.15)
				)
			)
		)
		(property "Author" "Antmicro"
			(at 0 0 0)
			(layer "B.Fab")
			(hide yes)
			(effects
				(font
					(size 1 1)
					(thickness 0.15)
				)
				(justify mirror)
			)
		)
		(property "Dielectric" ""
			(at 0 0 0)
			(layer "B.Fab")
			(hide yes)
			(effects
				(font
					(size 1 1)
					(thickness 0.15)
				)
				(justify mirror)
			)
		)
		(property "License" "Apache-2.0"
			(at 0 0 0)
			(layer "B.Fab")
			(hide yes)
			(effects
				(font
					(size 1 1)
					(thickness 0.15)
				)
				(justify mirror)
			)
		)
		(property "MPN" "C1608X5R1V475M080AC"
			(at 0 0 0)
			(layer "B.Fab")
			(hide yes)
			(effects
				(font
					(size 1 1)
					(thickness 0.15)
				)
				(justify mirror)
			)
		)
		(property "Manufacturer" "TDK"
			(at 0 0 0)
			(layer "B.Fab")
			(hide yes)
			(effects
				(font
					(size 1 1)
					(thickness 0.15)
				)
				(justify mirror)
			)
		)
		(property "Val" "4u7"
			(at 0 0 0)
			(layer "B.Fab")
			(hide yes)
			(effects
				(font
					(size 1 1)
					(thickness 0.15)
				)
				(justify mirror)
			)
		)
		(property "Voltage" ""
			(at 0 0 0)
			(layer "B.Fab")
			(hide yes)
			(effects
				(font
					(size 1 1)
					(thickness 0.15)
				)
				(justify mirror)
			)
		)
		(sheetname "/Interfaces/")
		(sheetfile "interfaces.kicad_sch")
		(attr smd)
		(fp_line
			(start -0.15 -0.4)
			(end 0.15 -0.4)
			(stroke
				(width 0.15)
				(type solid)
			)
			(layer "B.SilkS")
		)
		(fp_line
			(start -0.15 0.4)
			(end 0.15 0.4)
			(stroke
				(width 0.15)
				(type solid)
			)
			(layer "B.SilkS")
		)
		(fp_rect
			(start -1.25 0.65)
			(end 1.25 -0.65)
			(stroke
				(width 0.05)
				(type solid)
			)
			(fill no)
			(layer "B.CrtYd")
		)
		(fp_rect
			(start -0.8 0.4)
			(end 0.8 -0.4)
			(stroke
				(width 0.15)
				(type solid)
			)
			(fill no)
			(layer "B.Fab")
		)
		(pad "1" smd roundrect
			(at -0.7 0)
			(size 0.8 1)
			(layers "B.Cu" "B.Mask" "B.Paste")
			(roundrect_rratio 0.2)
			(net 1 "GND")
			(pintype "passive")
		)
		(pad "2" smd roundrect
			(at 0.7 0)
			(size 0.8 1)
			(layers "B.Cu" "B.Mask" "B.Paste")
			(roundrect_rratio 0.2)
			(net 6 "VCC1V0")
			(pintype "passive")
		)
	)
)
